# BASEBOARD_FAB2 (Tioga Pass) — schematic netlist excerpt (pin names and nets, part order shuffled) for the footprints in the layout excerpt that follows; sources: Cadence DE-HDL packaged netlist, KiCad conversion of Wiwynn_Tioga_Pass_MB.brd

J4A2  SCONN288_H44441004  SCONN  pkg PIP  page 51
  \12v\(1)  = P12V_NVDIMM_DEF
  VSS(93)  = GND
  DQ(4)  = M_E_DQ<5>
  VSS(92)  = GND
  DQ(0)  = M_E_DQ<1>
  VSS(91)  = GND
  DQS9P  = M_E_DQS_DP<9>
  DQS9N  = M_E_DQS_DN<9>
  VSS(90)  = GND
  DQ(6)  = M_E_DQ<7>
  VSS(89)  = GND
  DQ(2)  = M_E_DQ<3>
  VSS(88)  = GND
  DQ(12)  = M_E_DQ<13>
  VSS(87)  = GND
  DQ(8)  = M_E_DQ<9>
  VSS(86)  = GND
  DQS10P  = M_E_DQS_DP<10>
  DQS10N  = M_E_DQS_DN<10>
  VSS(85)  = GND
  DQ(14)  = M_E_DQ<15>
  VSS(84)  = GND
  DQ(10)  = M_E_DQ<11>
  VSS(83)  = GND
  DQ(20)  = M_E_DQ<21>
  VSS(82)  = GND
  DQ(16)  = M_E_DQ<17>
  VSS(81)  = GND
  DQS11P  = M_E_DQS_DP<11>
  DQS11N  = M_E_DQS_DN<11>
  VSS(80)  = GND
  DQ(22)  = M_E_DQ<23>
  VSS(79)  = GND
  DQ(18)  = M_E_DQ<19>
  VSS(78)  = GND
  DQ(28)  = M_E_DQ<29>
  VSS(77)  = GND
  DQ(24)  = M_E_DQ<25>
  VSS(76)  = GND
  DQS12P  = M_E_DQS_DP<12>
  DQS12N  = M_E_DQS_DN<12>
  VSS(75)  = GND
  DQ(30)  = M_E_DQ<31>
  VSS(74)  = GND
  DQ(26)  = M_E_DQ<27>
  VSS(73)  = GND
  CB(4)  = M_E_ECC<5>
  VSS(72)  = GND
  CB(0)  = M_E_ECC<1>
  VSS(71)  = GND
  DQS17P  = M_E_DQS_DP<17>
  DQS17N  = M_E_DQS_DN<17>
  VSS(70)  = GND
  CB(6)  = M_E_ECC<7>
  VSS(69)  = GND
  CB(2)  = M_E_ECC<3>
  VSS(68)  = GND
  RESET_N  = M_DEF_RST_N
  VDD(25)  = PVDDQ_DEF
  CKE(0)  = M_E_CKE<0>
  VDD(24)  = PVDDQ_DEF
  ACT_N  = M_E_ACT_N
  BG(0)  = M_E_BG<0>
  VDD(23)  = PVDDQ_DEF
  A12  = M_E_MA<12>
  A9  = M_E_MA<9>
  VDD(22)  = PVDDQ_DEF
  A8  = M_E_MA<8>
  A6  = M_E_MA<6>
  VDD(21)  = PVDDQ_DEF
  A3  = M_E_MA<3>
  A1  = M_E_MA<1>
  VDD(20)  = PVDDQ_DEF
  CK0P  = M_E_CLK_DP<0>
  CK0N  = M_E_CLK_DN<0>
  VDD(19)  = PVDDQ_DEF
  VTT(1)  = PVTT_DEF
  EVENT_N  = FM_DIMM_EVENT_COD_N
  A0  = M_E_MA<0>
  VDD(18)  = PVDDQ_DEF
  BA(0)  = M_E_BA<0>
  A16_RAS_N  = M_E_MA<16>
  VDD(17)  = PVDDQ_DEF
  S0_N  = M_E_CS_N<0>
  VDD(16)  = PVDDQ_DEF
  A15_CAS_N  = M_E_MA<15>
  ODT(0)  = M_E_ODT<0>
  VDD(15)  = PVDDQ_DEF
  S1_N  = M_E_CS_N<1>
  VDD(14)  = PVDDQ_DEF
  ODT(1)  = M_E_ODT<1>
  VDD(13)  = PVDDQ_DEF
  S2_N_C(0)  = M_E_CS_N<2>
  VSS(67)  = GND
  DQ(36)  = M_E_DQ<37>
  VSS(66)  = GND
  DQ(32)  = M_E_DQ<33>
  VSS(65)  = GND
  DQS13P  = M_E_DQS_DP<13>
  DQS13N  = M_E_DQS_DN<13>
  VSS(64)  = GND
  DQ(38)  = M_E_DQ<39>
  VSS(63)  = GND
  DQ(34)  = M_E_DQ<35>
  VSS(62)  = GND
  DQ(44)  = M_E_DQ<45>
  VSS(61)  = GND
  DQ(40)  = M_E_DQ<41>
  VSS(60)  = GND
  DQS14P  = M_E_DQS_DP<14>
  DQS14N  = M_E_DQS_DN<14>
  VSS(59)  = GND
  DQ(46)  = M_E_DQ<47>
  VSS(58)  = GND
  DQ(42)  = M_E_DQ<43>
  VSS(57)  = GND
  DQ(52)  = M_E_DQ<53>
  VSS(56)  = GND
  DQ(48)  = M_E_DQ<49>
  VSS(55)  = GND
  DQS15P  = M_E_DQS_DP<15>
  DQS15N  = M_E_DQS_DN<15>
  VSS(54)  = GND
  DQ(54)  = M_E_DQ<55>
  VSS(53)  = GND
  DQ(50)  = M_E_DQ<51>
  VSS(52)  = GND
  DQ(60)  = M_E_DQ<61>
  VSS(51)  = GND
  DQ(56)  = M_E_DQ<57>
  VSS(50)  = GND
  DQS16P  = M_E_DQS_DP<16>
  DQS16N  = M_E_DQS_DN<16>
  VSS(49)  = GND
  DQ(62)  = M_E_DQ<63>
  VSS(48)  = GND
  DQ(58)  = M_E_DQ<59>
  VSS(47)  = GND
  SA(0)  = GND
  SA(1)  = PVPP_DEF
  SCL  = SMB_DDR_DEF_VPP_SCL
  VPP(4)  = PVPP_DEF
  VPP(3)  = PVPP_DEF
  RFU(2)  = TP_CH_E_DIMM_E0_RFU_2
  \12v\(0)  = P12V_NVDIMM_DEF
  VREFCA  = M_E_VREF
  VSS(46)  = GND
  DQ(5)  = M_E_DQ<4>
  VSS(45)  = GND
  DQ(1)  = M_E_DQ<0>
  VSS(44)  = GND
  DQS0N  = M_E_DQS_DN<0>
  DQS0P  = M_E_DQS_DP<0>
  VSS(43)  = GND
  DQ(7)  = M_E_DQ<6>
  VSS(42)  = GND
  DQ(3)  = M_E_DQ<2>
  VSS(41)  = GND
  DQ(13)  = M_E_DQ<12>
  VSS(40)  = GND
  DQ(9)  = M_E_DQ<8>
  VSS(39)  = GND
  DQS1N  = M_E_DQS_DN<1>
  DQS1P  = M_E_DQS_DP<1>
  VSS(38)  = GND
  DQ(15)  = M_E_DQ<14>
  VSS(37)  = GND
  DQ(11)  = M_E_DQ<10>
  VSS(36)  = GND
  DQ(21)  = M_E_DQ<20>
  VSS(35)  = GND
  DQ(17)  = M_E_DQ<16>
  VSS(34)  = GND
  DQS2N  = M_E_DQS_DN<2>
  DQS2P  = M_E_DQS_DP<2>
  VSS(33)  = GND
  DQ(23)  = M_E_DQ<22>
  VSS(32)  = GND
  DQ(19)  = M_E_DQ<18>
  VSS(31)  = GND
  DQ(29)  = M_E_DQ<28>
  VSS(30)  = GND
  DQ(25)  = M_E_DQ<24>
  VSS(29)  = GND
  DQS3N  = M_E_DQS_DN<3>
  DQS3P  = M_E_DQS_DP<3>
  VSS(28)  = GND
  DQ(31)  = M_E_DQ<30>
  VSS(27)  = GND
  DQ(27)  = M_E_DQ<26>
  VSS(26)  = GND
  CB(5)  = M_E_ECC<4>
  VSS(25)  = GND
  CB(1)  = M_E_ECC<0>
  VSS(24)  = GND
  DQS8N  = M_E_DQS_DN<8>
  DQS8P  = M_E_DQS_DP<8>
  VSS(23)  = GND
  CB(7)  = M_E_ECC<6>
  VSS(22)  = GND
  CB(3)  = M_E_ECC<2>
  VSS(21)  = GND
  CKE(1)  = M_E_CKE<1>
  VDD(12)  = PVDDQ_DEF
  RFU(0)  = TP_CH_E_DIMM_E0_RFU_0
  VDD(11)  = PVDDQ_DEF
  BG(1)  = M_E_BG<1>
  ALERT_N  = M_E_ALERT_N
  VDD(10)  = PVDDQ_DEF
  A11  = M_E_MA<11>
  A7  = M_E_MA<7>
  VDD(9)  = PVDDQ_DEF
  A5  = M_E_MA<5>
  A4  = M_E_MA<4>
  VDD(8)  = PVDDQ_DEF
  A2  = M_E_MA<2>
  VDD(7)  = PVDDQ_DEF
  CK1P  = M_E_CLK_DP<1>
  CK1N  = M_E_CLK_DN<1>
  VDD(6)  = PVDDQ_DEF
  VTT(0)  = PVTT_DEF
  PAR  = M_E_PAR
  VDD(5)  = PVDDQ_DEF
  BA(1)  = M_E_BA<1>
  A10  = M_E_MA<10>
  VDD(4)  = PVDDQ_DEF
  RFU(1)  = TP_CH_E_DIMM_E0_RFU_1
  A14_WE_N  = M_E_MA<14>
  VDD(3)  = PVDDQ_DEF
  SAVE_N_NC  = FM_ADR_COMPLETE_DEF_N
  VDD(2)  = PVDDQ_DEF
  A13  = M_E_MA<13>
  VDD(1)  = PVDDQ_DEF
  A17  = M_E_MA<17>
  C(2)  = M_E_C<2>
  VDD(0)  = PVDDQ_DEF
  S3_N_C(1)  = M_E_CS_N<3>
  SA(2)  = GND
  VSS(20)  = GND
  DQ(37)  = M_E_DQ<36>
  VSS(19)  = GND
  DQ(33)  = M_E_DQ<32>
  VSS(18)  = GND
  DQS4N  = M_E_DQS_DN<4>
  DQS4P  = M_E_DQS_DP<4>
  VSS(17)  = GND
  DQ(39)  = M_E_DQ<38>
  VSS(16)  = GND
  DQ(35)  = M_E_DQ<34>
  VSS(15)  = GND
  DQ(45)  = M_E_DQ<44>
  VSS(14)  = GND
  DQ(41)  = M_E_DQ<40>
  VSS(13)  = GND
  DQS5N  = M_E_DQS_DN<5>
  DQS5P  = M_E_DQS_DP<5>
  VSS(12)  = GND
  DQ(47)  = M_E_DQ<46>
  VSS(11)  = GND
  DQ(43)  = M_E_DQ<42>
  VSS(10)  = GND
  DQ(53)  = M_E_DQ<52>
  VSS(9)  = GND
  DQ(49)  = M_E_DQ<48>
  VSS(8)  = GND
  DQS6N  = M_E_DQS_DN<6>
  DQS6P  = M_E_DQS_DP<6>
  VSS(7)  = GND
  DQ(55)  = M_E_DQ<54>
  VSS(6)  = GND
  DQ(51)  = M_E_DQ<50>
  VSS(5)  = GND
  DQ(61)  = M_E_DQ<60>
  VSS(4)  = GND
  DQ(57)  = M_E_DQ<56>
  VSS(3)  = GND
  DQS7N  = M_E_DQS_DN<7>
  DQS7P  = M_E_DQS_DP<7>
  VSS(2)  = GND
  DQ(63)  = M_E_DQ<62>
  VSS(1)  = GND
  DQ(59)  = M_E_DQ<58>
  VSS(0)  = GND
  VDDSPD  = PVPP_DEF
  SDA  = SMB_DDR_DEF_VPP_SDA
  VPP(1)  = PVPP_DEF
  VPP(0)  = PVPP_DEF
  VPP(2)  = PVPP_DEF

(kicad_pcb
	(version 20260206)
	(generator "pcbnew")
	(generator_version "10.0")
	(general
		(thickness 1.6)
		(legacy_teardrops no)
	)
	(paper "A4")
	(title_block
		(title "Wiwynn_Tioga_Pass_MB.brd")
		(comment 1 "Tioga Pass / footprint 2096 of 4770 (J4A2), pads 52-101 of 291")
	)
	(layers
		(0 "F.Cu" signal "TOP")
		(4 "In1.Cu" signal "L2GND")
		(6 "In2.Cu" signal "L3")
		(8 "In3.Cu" signal "L4GND")
		(10 "In4.Cu" signal "L5")
		(12 "In5.Cu" signal "L6GND")
		(14 "In6.Cu" signal "L7VCC")
		(16 "In7.Cu" signal "L8VCC")
		(18 "In8.Cu" signal "L9GND")
		(20 "In9.Cu" signal "L10")
		(22 "In10.Cu" signal "L11GND")
		(24 "In11.Cu" signal "L12")
		(26 "In12.Cu" signal "L13GND")
		(2 "B.Cu" signal "BOTTOM")
		(9 "F.Adhes" user "F.Adhesive")
		(11 "B.Adhes" user "B.Adhesive")
		(13 "F.Paste" user "Package Geometry/Pastemask Top")
		(15 "B.Paste" user "Package Geometry/Pastemask Bottom")
		(5 "F.SilkS" user "Ref Des/Silkscreen Top")
		(7 "B.SilkS" user "Ref Des/Silkscreen Bottom")
		(1 "F.Mask" user "Board Geometry/Soldermask Top")
		(3 "B.Mask" user "Board Geometry/Soldermask Bottom")
		(17 "Dwgs.User" user "User.Drawings")
		(19 "Cmts.User" user "User.Comments")
		(21 "Eco1.User" user "User.Eco1")
		(23 "Eco2.User" user "User.Eco2")
		(25 "Edge.Cuts" user "Board Geometry/Outline")
		(27 "Margin" user)
		(31 "F.CrtYd" user "Package Geometry/Place Bound Top")
		(29 "B.CrtYd" user "Package Geometry/Place Bound Bottom")
		(35 "F.Fab" user "Ref Des/Assembly Top")
		(33 "B.Fab" user "Ref Des/Assembly Bottom")
	)
	(footprint ""
		(layer "F.Cu")
		(at 194.700398 -142.6718 90)
		(property "Reference" "J4A2"
			(at -2.369312 42.66311 0)
			(unlocked yes)
			(layer "F.SilkS")
			(effects
				(font
					(size 0.7874 0.5842)
					(thickness 0.1524)
				)
				(justify left)
			)
		)
		(property "Value" ""
			(at 0 0 90)
			(layer "F.Fab")
			(effects
				(font
					(size 1.27 1.27)
				)
			)
		)
		(duplicate_pad_numbers_are_jumpers no)
		(pad "49" smd rect
			(at 0 40.80002 90)
			(size 1.8034 0.508)
			(layers "F.Cu" "F.Mask" "F.Paste")
			(net "M_E_ECC<1>")
		)
		(pad "50" smd rect
			(at 0 41.649904 90)
			(size 1.8034 0.508)
			(layers "F.Cu" "F.Mask" "F.Paste")
			(net "GND")
		)
		(pad "51" smd rect
			(at 0 42.500042 90)
			(size 1.8034 0.508)
			(layers "F.Cu" "F.Mask" "F.Paste")
			(net "M_E_DQS_DP<17>")
		)
		(pad "52" smd rect
			(at 0 43.349926 90)
			(size 1.8034 0.508)
			(layers "F.Cu" "F.Mask" "F.Paste")
			(net "M_E_DQS_DN<17>")
		)
		(pad "53" smd rect
			(at 0 44.200064 90)
			(size 1.8034 0.508)
			(layers "F.Cu" "F.Mask" "F.Paste")
			(net "GND")
		)
		(pad "54" smd rect
			(at 0 45.049948 90)
			(size 1.8034 0.508)
			(layers "F.Cu" "F.Mask" "F.Paste")
			(net "M_E_ECC<7>")
		)
		(pad "55" smd rect
			(at 0 45.900086 90)
			(size 1.8034 0.508)
			(layers "F.Cu" "F.Mask" "F.Paste")
			(net "GND")
		)
		(pad "56" smd rect
			(at 0 46.74997 90)
			(size 1.8034 0.508)
			(layers "F.Cu" "F.Mask" "F.Paste")
			(net "M_E_ECC<3>")
		)
		(pad "57" smd rect
			(at 0 47.600108 90)
			(size 1.8034 0.508)
			(layers "F.Cu" "F.Mask" "F.Paste")
			(net "GND")
		)
		(pad "58" smd rect
			(at 0 48.449992 90)
			(size 1.8034 0.508)
			(layers "F.Cu" "F.Mask" "F.Paste")
			(net "M_DEF_RST_N")
		)
		(pad "59" smd rect
			(at 0 49.299876 90)
			(size 1.8034 0.508)
			(layers "F.Cu" "F.Mask" "F.Paste")
			(net "PVDDQ_DEF")
		)
		(pad "60" smd rect
			(at 0 50.150014 90)
			(size 1.8034 0.508)
			(layers "F.Cu" "F.Mask" "F.Paste")
			(net "M_E_CKE<0>")
		)
		(pad "61" smd rect
			(at 0 50.999898 90)
			(size 1.8034 0.508)
			(layers "F.Cu" "F.Mask" "F.Paste")
			(net "PVDDQ_DEF")
		)
		(pad "62" smd rect
			(at 0 51.850036 90)
			(size 1.8034 0.508)
			(layers "F.Cu" "F.Mask" "F.Paste")
			(net "M_E_ACT_N")
		)
		(pad "63" smd rect
			(at 0 52.69992 90)
			(size 1.8034 0.508)
			(layers "F.Cu" "F.Mask" "F.Paste")
			(net "M_E_BG<0>")
		)
		(pad "64" smd rect
			(at 0 53.550058 90)
			(size 1.8034 0.508)
			(layers "F.Cu" "F.Mask" "F.Paste")
			(net "PVDDQ_DEF")
		)
		(pad "65" smd rect
			(at 0 54.399942 90)
			(size 1.8034 0.508)
			(layers "F.Cu" "F.Mask" "F.Paste")
			(net "M_E_MA<12>")
		)
		(pad "66" smd rect
			(at 0 55.25008 90)
			(size 1.8034 0.508)
			(layers "F.Cu" "F.Mask" "F.Paste")
			(net "M_E_MA<9>")
		)
		(pad "67" smd rect
			(at 0 56.099964 90)
			(size 1.8034 0.508)
			(layers "F.Cu" "F.Mask" "F.Paste")
			(net "PVDDQ_DEF")
		)
		(pad "68" smd rect
			(at 0 56.950102 90)
			(size 1.8034 0.508)
			(layers "F.Cu" "F.Mask" "F.Paste")
			(net "M_E_MA<8>")
		)
		(pad "69" smd rect
			(at 0 57.799986 90)
			(size 1.8034 0.508)
			(layers "F.Cu" "F.Mask" "F.Paste")
			(net "M_E_MA<6>")
		)
		(pad "70" smd rect
			(at 0 58.650124 90)
			(size 1.8034 0.508)
			(layers "F.Cu" "F.Mask" "F.Paste")
			(net "PVDDQ_DEF")
		)
		(pad "71" smd rect
			(at 0 59.500008 90)
			(size 1.8034 0.508)
			(layers "F.Cu" "F.Mask" "F.Paste")
			(net "M_E_MA<3>")
		)
		(pad "72" smd rect
			(at 0 60.349892 90)
			(size 1.8034 0.508)
			(layers "F.Cu" "F.Mask" "F.Paste")
			(net "M_E_MA<1>")
		)
		(pad "73" smd rect
			(at 0 61.20003 90)
			(size 1.8034 0.508)
			(layers "F.Cu" "F.Mask" "F.Paste")
			(net "PVDDQ_DEF")
		)
		(pad "74" smd rect
			(at 0 62.049914 90)
			(size 1.8034 0.508)
			(layers "F.Cu" "F.Mask" "F.Paste")
			(net "M_E_CLK_DP<0>")
		)
		(pad "75" smd rect
			(at 0 62.900052 90)
			(size 1.8034 0.508)
			(layers "F.Cu" "F.Mask" "F.Paste")
			(net "M_E_CLK_DN<0>")
		)
		(pad "76" smd rect
			(at 0 63.749936 90)
			(size 1.8034 0.508)
			(layers "F.Cu" "F.Mask" "F.Paste")
			(net "PVDDQ_DEF")
		)
		(pad "77" smd rect
			(at 0 64.600074 90)
			(size 1.8034 0.508)
			(layers "F.Cu" "F.Mask" "F.Paste")
			(net "PVTT_DEF")
		)
		(pad "78" smd rect
			(at 0 70.550024 90)
			(size 1.8034 0.508)
			(layers "F.Cu" "F.Mask" "F.Paste")
			(net "FM_DIMM_EVENT_COD_N")
		)
		(pad "79" smd rect
			(at 0 71.399908 90)
			(size 1.8034 0.508)
			(layers "F.Cu" "F.Mask" "F.Paste")
			(net "M_E_MA<0>")
		)
		(pad "80" smd rect
			(at 0 72.250046 90)
			(size 1.8034 0.508)
			(layers "F.Cu" "F.Mask" "F.Paste")
			(net "PVDDQ_DEF")
		)
		(pad "81" smd rect
			(at 0 73.09993 90)
			(size 1.8034 0.508)
			(layers "F.Cu" "F.Mask" "F.Paste")
			(net "M_E_BA<0>")
		)
		(pad "82" smd rect
			(at 0 73.950068 90)
			(size 1.8034 0.508)
			(layers "F.Cu" "F.Mask" "F.Paste")
			(net "M_E_MA<16>")
		)
		(pad "83" smd rect
			(at 0 74.799952 90)
			(size 1.8034 0.508)
			(layers "F.Cu" "F.Mask" "F.Paste")
			(net "PVDDQ_DEF")
		)
		(pad "84" smd rect
			(at 0 75.65009 90)
			(size 1.8034 0.508)
			(layers "F.Cu" "F.Mask" "F.Paste")
			(net "M_E_CS_N<0>")
		)
		(pad "85" smd rect
			(at 0 76.499974 90)
			(size 1.8034 0.508)
			(layers "F.Cu" "F.Mask" "F.Paste")
			(net "PVDDQ_DEF")
		)
		(pad "86" smd rect
			(at 0 77.350112 90)
			(size 1.8034 0.508)
			(layers "F.Cu" "F.Mask" "F.Paste")
			(net "M_E_MA<15>")
		)
		(pad "87" smd rect
			(at 0 78.199996 90)
			(size 1.8034 0.508)
			(layers "F.Cu" "F.Mask" "F.Paste")
			(net "M_E_ODT<0>")
		)
		(pad "88" smd rect
			(at 0 79.04988 90)
			(size 1.8034 0.508)
			(layers "F.Cu" "F.Mask" "F.Paste")
			(net "PVDDQ_DEF")
		)
		(pad "89" smd rect
			(at 0 79.900018 90)
			(size 1.8034 0.508)
			(layers "F.Cu" "F.Mask" "F.Paste")
			(net "M_E_CS_N<1>")
		)
		(pad "90" smd rect
			(at 0 80.749902 90)
			(size 1.8034 0.508)
			(layers "F.Cu" "F.Mask" "F.Paste")
			(net "PVDDQ_DEF")
		)
		(pad "91" smd rect
			(at 0 81.60004 90)
			(size 1.8034 0.508)
			(layers "F.Cu" "F.Mask" "F.Paste")
			(net "M_E_ODT<1>")
		)
		(pad "92" smd rect
			(at 0 82.449924 90)
			(size 1.8034 0.508)
			(layers "F.Cu" "F.Mask" "F.Paste")
			(net "PVDDQ_DEF")
		)
		(pad "93" smd rect
			(at 0 83.300062 90)
			(size 1.8034 0.508)
			(layers "F.Cu" "F.Mask" "F.Paste")
			(net "M_E_CS_N<2>")
		)
		(pad "94" smd rect
			(at 0 84.149946 90)
			(size 1.8034 0.508)
			(layers "F.Cu" "F.Mask" "F.Paste")
			(net "GND")
		)
		(pad "95" smd rect
			(at 0 85.000084 90)
			(size 1.8034 0.508)
			(layers "F.Cu" "F.Mask" "F.Paste")
			(net "M_E_DQ<37>")
		)
		(pad "96" smd rect
			(at 0 85.849968 90)
			(size 1.8034 0.508)
			(layers "F.Cu" "F.Mask" "F.Paste")
			(net "GND")
		)
		(pad "97" smd rect
			(at 0 86.700106 90)
			(size 1.8034 0.508)
			(layers "F.Cu" "F.Mask" "F.Paste")
			(net "M_E_DQ<33>")
		)
		(pad "98" smd rect
			(at 0 87.54999 90)
			(size 1.8034 0.508)
			(layers "F.Cu" "F.Mask" "F.Paste")
			(net "GND")
		)
	)
)
